# T6G (Grand Teton) — schematic netlist excerpt (pin names and nets, part order shuffled) for the footprints in the layout excerpt that follows; sources: Cadence DE-HDL packaged netlist, KiCad conversion of 04192023_DAF0TMB3IC0_F0TG_MB_C_brd_V02_OCP.brd

C317  Q_CAP  100UF 4V 20% X6S  pkg C0805  page 334 : A = P0V9_CPU1_RT1_2A ; B = GND
C199  Q_CAP  10UF 6.3V 20% X6S  pkg C0402  page 334 : A = P1V8_CPU1_RT1_1A ; B = GND
R489  Q_RES  33 5% CHIP  pkg 0402LF  page 27 : A = CPU0_THERMTRIP_N ; B = CPU0_THERMTRIP_R_N

(kicad_pcb
	(version 20260206)
	(generator "pcbnew")
	(generator_version "10.0")
	(general
		(thickness 1.6)
		(legacy_teardrops no)
	)
	(paper "A4")
	(title_block
		(title "04192023_DAF0TMB3IC0_F0TG_MB_C_brd_V02_OCP.brd")
		(comment 1 "Grand Teton / footprints 5986-5988 of 8354")
	)
	(layers
		(0 "F.Cu" signal "TOP")
		(4 "In1.Cu" signal "GND")
		(6 "In2.Cu" signal "IN1")
		(8 "In3.Cu" signal "GND1")
		(10 "In4.Cu" signal "IN2")
		(12 "In5.Cu" signal "GND2")
		(14 "In6.Cu" signal "IN3")
		(16 "In7.Cu" signal "GND3")
		(18 "In8.Cu" signal "VCC")
		(20 "In9.Cu" signal "VCC1")
		(22 "In10.Cu" signal "GND4")
		(24 "In11.Cu" signal "IN4")
		(26 "In12.Cu" signal "GND5")
		(28 "In13.Cu" signal "IN5")
		(30 "In14.Cu" signal "GND6")
		(32 "In15.Cu" signal "IN6")
		(34 "In16.Cu" signal "GND7")
		(2 "B.Cu" signal "BOTTOM")
		(9 "F.Adhes" user "F.Adhesive")
		(11 "B.Adhes" user "B.Adhesive")
		(13 "F.Paste" user "Package Geometry/Pastemask Top")
		(15 "B.Paste" user "Package Geometry/Pastemask Bottom")
		(5 "F.SilkS" user "Ref Des/Silkscreen Top")
		(7 "B.SilkS" user "Ref Des/Silkscreen Bottom")
		(1 "F.Mask" user "Board Geometry/Soldermask Top")
		(3 "B.Mask" user "Board Geometry/Soldermask Bottom")
		(17 "Dwgs.User" user "User.Drawings")
		(19 "Cmts.User" user "User.Comments")
		(21 "Eco1.User" user "User.Eco1")
		(23 "Eco2.User" user "User.Eco2")
		(25 "Edge.Cuts" user "Board Geometry/Outline")
		(27 "Margin" user)
		(31 "F.CrtYd" user "Package Geometry/Place Bound Top")
		(29 "B.CrtYd" user "Package Geometry/Place Bound Bottom")
		(35 "F.Fab" user "Ref Des/Assembly Top")
		(33 "B.Fab" user "Ref Des/Assembly Bottom")
	)
	(footprint ""
		(layer "B.Cu")
		(at 181.534562 -97.123504 -90)
		(property "Reference" "R489"
			(at 0 0 90)
			(layer "B.SilkS")
			(hide yes)
			(effects
				(font
					(size 1.27 1.27)
				)
				(justify mirror)
			)
		)
		(property "Value" ""
			(at 0 0 90)
			(layer "B.Fab")
			(effects
				(font
					(size 1.27 1.27)
				)
				(justify mirror)
			)
		)
		(duplicate_pad_numbers_are_jumpers no)
		(fp_line
			(start -0.7874 0.4064)
			(end 0.7874 0.4064)
			(stroke
				(width 0.1524)
				(type default)
			)
			(layer "B.SilkS")
		)
		(fp_line
			(start 0.7874 0.4064)
			(end 0.7874 -0.4064)
			(stroke
				(width 0.1524)
				(type default)
			)
			(layer "B.SilkS")
		)
		(fp_line
			(start -0.7874 -0.4064)
			(end -0.7874 0.4064)
			(stroke
				(width 0.1524)
				(type default)
			)
			(layer "B.SilkS")
		)
		(fp_line
			(start 0.7874 -0.4064)
			(end -0.7874 -0.4064)
			(stroke
				(width 0.1524)
				(type default)
			)
			(layer "B.SilkS")
		)
		(fp_line
			(start -0.67945 0.3048)
			(end -0.120396 0.3048)
			(stroke
				(width 0.1)
				(type default)
			)
			(layer "B.Fab")
		)
		(fp_line
			(start -0.120396 0.3048)
			(end -0.120396 0.2794)
			(stroke
				(width 0.1)
				(type default)
			)
			(layer "B.Fab")
		)
		(fp_line
			(start 0.12065 0.3048)
			(end 0.67945 0.3048)
			(stroke
				(width 0.1)
				(type default)
			)
			(layer "B.Fab")
		)
		(fp_line
			(start 0.67945 0.3048)
			(end 0.67945 -0.305054)
			(stroke
				(width 0.1)
				(type default)
			)
			(layer "B.Fab")
		)
		(fp_line
			(start -0.120396 0.2794)
			(end 0.12065 0.2794)
			(stroke
				(width 0.1)
				(type default)
			)
			(layer "B.Fab")
		)
		(fp_line
			(start 0.12065 0.2794)
			(end 0.12065 0.3048)
			(stroke
				(width 0.1)
				(type default)
			)
			(layer "B.Fab")
		)
		(fp_line
			(start -0.12065 -0.2794)
			(end -0.12065 -0.3048)
			(stroke
				(width 0.1)
				(type default)
			)
			(layer "B.Fab")
		)
		(fp_line
			(start 0.12065 -0.2794)
			(end -0.12065 -0.2794)
			(stroke
				(width 0.1)
				(type default)
			)
			(layer "B.Fab")
		)
		(fp_line
			(start -0.67945 -0.3048)
			(end -0.67945 0.3048)
			(stroke
				(width 0.1)
				(type default)
			)
			(layer "B.Fab")
		)
		(fp_line
			(start -0.12065 -0.3048)
			(end -0.67945 -0.3048)
			(stroke
				(width 0.1)
				(type default)
			)
			(layer "B.Fab")
		)
		(fp_line
			(start 0.12065 -0.305054)
			(end 0.12065 -0.2794)
			(stroke
				(width 0.1)
				(type default)
			)
			(layer "B.Fab")
		)
		(fp_line
			(start 0.67945 -0.305054)
			(end 0.12065 -0.305054)
			(stroke
				(width 0.1)
				(type default)
			)
			(layer "B.Fab")
		)
		(pad "1" smd circle
			(at 0.40005 0 90)
			(size 0 0)
			(layers "B.Cu" "B.Mask" "B.Paste")
			(net "CPU0_THERMTRIP_N")
		)
		(pad "2" smd circle
			(at -0.40005 0 90)
			(size 0 0)
			(layers "B.Cu" "B.Mask" "B.Paste")
			(net "CPU0_THERMTRIP_R_N")
		)
	)
	(footprint ""
		(layer "B.Cu")
		(at 89.518998 -390.560052 90)
		(property "Reference" "C199"
			(at 0 0 90)
			(layer "B.SilkS")
			(hide yes)
			(effects
				(font
					(size 1.27 1.27)
				)
				(justify mirror)
			)
		)
		(property "Value" ""
			(at 0 0 90)
			(layer "B.Fab")
			(effects
				(font
					(size 1.27 1.27)
				)
				(justify mirror)
			)
		)
		(duplicate_pad_numbers_are_jumpers no)
		(fp_line
			(start 0.7874 -0.4064)
			(end -0.7874 -0.4064)
			(stroke
				(width 0.1524)
				(type default)
			)
			(layer "B.SilkS")
		)
		(fp_line
			(start -0.7874 -0.4064)
			(end -0.7874 0.4064)
			(stroke
				(width 0.1524)
				(type default)
			)
			(layer "B.SilkS")
		)
		(fp_line
			(start 0.7874 0.4064)
			(end 0.7874 -0.4064)
			(stroke
				(width 0.1524)
				(type default)
			)
			(layer "B.SilkS")
		)
		(fp_line
			(start -0.7874 0.4064)
			(end 0.7874 0.4064)
			(stroke
				(width 0.1524)
				(type default)
			)
			(layer "B.SilkS")
		)
		(fp_line
			(start 0.67945 -0.305054)
			(end 0.12065 -0.305054)
			(stroke
				(width 0.1)
				(type default)
			)
			(layer "B.Fab")
		)
		(fp_line
			(start 0.12065 -0.305054)
			(end 0.12065 -0.2794)
			(stroke
				(width 0.1)
				(type default)
			)
			(layer "B.Fab")
		)
		(fp_line
			(start -0.12065 -0.3048)
			(end -0.67945 -0.3048)
			(stroke
				(width 0.1)
				(type default)
			)
			(layer "B.Fab")
		)
		(fp_line
			(start -0.67945 -0.3048)
			(end -0.67945 0.3048)
			(stroke
				(width 0.1)
				(type default)
			)
			(layer "B.Fab")
		)
		(fp_line
			(start 0.12065 -0.2794)
			(end -0.12065 -0.2794)
			(stroke
				(width 0.1)
				(type default)
			)
			(layer "B.Fab")
		)
		(fp_line
			(start -0.12065 -0.2794)
			(end -0.12065 -0.3048)
			(stroke
				(width 0.1)
				(type default)
			)
			(layer "B.Fab")
		)
		(fp_line
			(start 0.12065 0.2794)
			(end 0.12065 0.3048)
			(stroke
				(width 0.1)
				(type default)
			)
			(layer "B.Fab")
		)
		(fp_line
			(start -0.120396 0.2794)
			(end 0.12065 0.2794)
			(stroke
				(width 0.1)
				(type default)
			)
			(layer "B.Fab")
		)
		(fp_line
			(start 0.67945 0.3048)
			(end 0.67945 -0.305054)
			(stroke
				(width 0.1)
				(type default)
			)
			(layer "B.Fab")
		)
		(fp_line
			(start 0.12065 0.3048)
			(end 0.67945 0.3048)
			(stroke
				(width 0.1)
				(type default)
			)
			(layer "B.Fab")
		)
		(fp_line
			(start -0.120396 0.3048)
			(end -0.120396 0.2794)
			(stroke
				(width 0.1)
				(type default)
			)
			(layer "B.Fab")
		)
		(fp_line
			(start -0.67945 0.3048)
			(end -0.120396 0.3048)
			(stroke
				(width 0.1)
				(type default)
			)
			(layer "B.Fab")
		)
		(pad "1" smd circle
			(at 0.40005 0 270)
			(size 0 0)
			(layers "B.Cu" "B.Mask" "B.Paste")
			(net "P1V8_CPU1_RT1_1A")
		)
		(pad "2" smd circle
			(at -0.40005 0 270)
			(size 0 0)
			(layers "B.Cu" "B.Mask" "B.Paste")
			(net "GND")
		)
	)
	(footprint ""
		(layer "B.Cu")
		(at 102.389432 -390.073134 180)
		(property "Reference" "C317"
			(at 0 0 0)
			(layer "B.SilkS")
			(hide yes)
			(effects
				(font
					(size 1.27 1.27)
				)
				(justify mirror)
			)
		)
		(property "Value" ""
			(at 0 0 0)
			(layer "B.Fab")
			(effects
				(font
					(size 1.27 1.27)
				)
				(justify mirror)
			)
		)
		(duplicate_pad_numbers_are_jumpers no)
		(fp_line
			(start 1.524 0.762)
			(end 1.524 -0.762)
			(stroke
				(width 0.1524)
				(type default)
			)
			(layer "B.SilkS")
		)
		(fp_line
			(start 1.524 -0.762)
			(end -1.524 -0.762)
			(stroke
				(width 0.1524)
				(type default)
			)
			(layer "B.SilkS")
		)
		(fp_line
			(start -1.524 0.762)
			(end 1.524 0.762)
			(stroke
				(width 0.1524)
				(type default)
			)
			(layer "B.SilkS")
		)
		(fp_line
			(start -1.524 -0.762)
			(end -1.524 0.762)
			(stroke
				(width 0.1524)
				(type default)
			)
			(layer "B.SilkS")
		)
		(fp_line
			(start 1.1049 0.724916)
			(end -1.1049 0.724916)
			(stroke
				(width 0.1)
				(type default)
			)
			(layer "B.Fab")
		)
		(fp_line
			(start 1.1049 -0.724916)
			(end 1.1049 0.724916)
			(stroke
				(width 0.1)
				(type default)
			)
			(layer "B.Fab")
		)
		(fp_line
			(start -1.1049 0.724916)
			(end -1.1049 -0.724916)
			(stroke
				(width 0.1)
				(type default)
			)
			(layer "B.Fab")
		)
		(fp_line
			(start -1.1049 -0.724916)
			(end 1.1049 -0.724916)
			(stroke
				(width 0.1)
				(type default)
			)
			(layer "B.Fab")
		)
		(pad "1" smd rect
			(at 0.889 0 180)
			(size 1.016 1.27)
			(layers "B.Cu" "B.Mask" "B.Paste")
			(net "P0V9_CPU1_RT1_2A")
		)
		(pad "2" smd rect
			(at -0.889 0 180)
			(size 1.016 1.27)
			(layers "B.Cu" "B.Mask" "B.Paste")
			(net "GND")
		)
	)
)
